(kicad_sch
	(version 20250114)
	(generator "eeschema")
	(generator_version "9.0")
	(paper "A3")
	(title_block
		(title "COM Express 7 Baseboard")
		(date "2025-02-04")
		(rev "1.1.2")
		(company "Antmicro Ltd")
		(comment 1 "www.antmicro.com")
	)
	(text "M.2 key M"
		(exclude_from_sim no)
		(at 198.12 27.94 0)
		(effects
			(font
				(size 2 2)
				(thickness 0.8)
				(bold yes)
			)
			(justify left bottom)
		)
	)
	(text "Swapped polarity of TX and RX lines\nfor easier PCB layout"
		(exclude_from_sim no)
		(at 163.83 173.99 0)
		(effects
			(font
				(size 1.27 1.27)
			)
			(justify left bottom)
		)
	)
	(junction
		(at 193.04 91.44)
		(diameter 0)
		(color 0 0 0 0)
	)
	(junction
		(at 184.15 81.28)
		(diameter 0)
		(color 0 0 0 0)
	)
	(junction
		(at 232.41 166.37)
		(diameter 0)
		(color 0 0 0 0)
	)
	(junction
		(at 267.97 85.09)
		(diameter 0)
		(color 0 0 0 0)
	)
	(junction
		(at 257.81 85.09)
		(diameter 0)
		(color 0 0 0 0)
	)
	(junction
		(at 247.65 85.09)
		(diameter 0)
		(color 0 0 0 0)
	)
	(junction
		(at 184.15 88.9)
		(diameter 0)
		(color 0 0 0 0)
	)
	(junction
		(at 237.49 85.09)
		(diameter 0)
		(color 0 0 0 0)
	)
	(no_connect
		(at 231.14 115.57)
	)
	(no_connect
		(at 231.14 120.65)
	)
	(no_connect
		(at 231.14 118.11)
	)
	(no_connect
		(at 200.66 93.98)
	)
	(bus_entry
		(at 156.21 162.56)
		(size 1.27 1.27)
		(stroke
			(width 0)
			(type default)
		)
	)
	(bus_entry
		(at 156.21 132.08)
		(size 1.27 1.27)
		(stroke
			(width 0)
			(type default)
		)
	)
	(bus_entry
		(at 156.21 109.22)
		(size 1.27 1.27)
		(stroke
			(width 0)
			(type default)
		)
	)
	(bus_entry
		(at 156.21 157.48)
		(size 1.27 1.27)
		(stroke
			(width 0)
			(type default)
		)
	)
	(bus_entry
		(at 156.21 111.76)
		(size 1.27 1.27)
		(stroke
			(width 0)
			(type default)
		)
	)
	(bus_entry
		(at 156.21 139.7)
		(size 1.27 1.27)
		(stroke
			(width 0)
			(type default)
		)
	)
	(bus_entry
		(at 156.21 124.46)
		(size 1.27 1.27)
		(stroke
			(width 0)
			(type default)
		)
	)
	(bus_entry
		(at 156.21 149.86)
		(size 1.27 1.27)
		(stroke
			(width 0)
			(type default)
		)
	)
	(bus_entry
		(at 182.88 101.6)
		(size -1.27 -1.27)
		(stroke
			(width 0)
			(type default)
		)
	)
	(bus_entry
		(at 156.21 119.38)
		(size 1.27 1.27)
		(stroke
			(width 0)
			(type default)
		)
	)
	(bus_entry
		(at 156.21 165.1)
		(size 1.27 1.27)
		(stroke
			(width 0)
			(type default)
		)
	)
	(bus_entry
		(at 156.21 154.94)
		(size 1.27 1.27)
		(stroke
			(width 0)
			(type default)
		)
	)
	(bus_entry
		(at 156.21 127)
		(size 1.27 1.27)
		(stroke
			(width 0)
			(type default)
		)
	)
	(bus_entry
		(at 156.21 142.24)
		(size 1.27 1.27)
		(stroke
			(width 0)
			(type default)
		)
	)
	(bus_entry
		(at 156.21 116.84)
		(size 1.27 1.27)
		(stroke
			(width 0)
			(type default)
		)
	)
	(bus_entry
		(at 156.21 147.32)
		(size 1.27 1.27)
		(stroke
			(width 0)
			(type default)
		)
	)
	(bus_entry
		(at 182.88 104.14)
		(size -1.27 -1.27)
		(stroke
			(width 0)
			(type default)
		)
	)
	(bus_entry
		(at 156.21 134.62)
		(size 1.27 1.27)
		(stroke
			(width 0)
			(type default)
		)
	)
	(wire
		(pts
			(xy 241.3 101.6) (xy 246.38 101.6)
		)
		(stroke
			(width 0)
			(type default)
		)
	)
	(bus
		(pts
			(xy 156.21 85.09) (xy 154.94 83.82)
		)
		(stroke
			(width 0)
			(type default)
		)
	)
	(wire
		(pts
			(xy 247.65 92.71) (xy 247.65 91.44)
		)
		(stroke
			(width 0)
			(type default)
		)
	)
	(wire
		(pts
			(xy 157.48 113.03) (xy 180.34 113.03)
		)
		(stroke
			(width 0)
			(type default)
		)
	)
	(wire
		(pts
			(xy 182.88 166.37) (xy 200.66 166.37)
		)
		(stroke
			(width 0)
			(type default)
		)
	)
	(wire
		(pts
			(xy 182.88 163.83) (xy 180.34 166.37)
		)
		(stroke
			(width 0)
			(type default)
		)
	)
	(wire
		(pts
			(xy 157.48 166.37) (xy 180.34 166.37)
		)
		(stroke
			(width 0)
			(type default)
		)
	)
	(wire
		(pts
			(xy 193.04 91.44) (xy 200.66 91.44)
		)
		(stroke
			(width 0)
			(type default)
		)
	)
	(bus
		(pts
			(xy 181.61 100.33) (xy 181.61 97.79)
		)
		(stroke
			(width 0)
			(type default)
		)
	)
	(wire
		(pts
			(xy 180.34 110.49) (xy 182.88 113.03)
		)
		(stroke
			(width 0)
			(type default)
		)
	)
	(wire
		(pts
			(xy 232.41 88.9) (xy 232.41 85.09)
		)
		(stroke
			(width 0)
			(type default)
		)
	)
	(wire
		(pts
			(xy 200.66 140.97) (xy 182.88 140.97)
		)
		(stroke
			(width 0)
			(type default)
		)
	)
	(bus
		(pts
			(xy 156.21 132.08) (xy 156.21 134.62)
		)
		(stroke
			(width 0)
			(type default)
		)
	)
	(wire
		(pts
			(xy 157.48 156.21) (xy 180.34 156.21)
		)
		(stroke
			(width 0)
			(type default)
		)
	)
	(wire
		(pts
			(xy 200.66 104.14) (xy 182.88 104.14)
		)
		(stroke
			(width 0)
			(type default)
		)
	)
	(bus
		(pts
			(xy 180.34 96.52) (xy 149.86 96.52)
		)
		(stroke
			(width 0)
			(type default)
		)
	)
	(wire
		(pts
			(xy 247.65 85.09) (xy 237.49 85.09)
		)
		(stroke
			(width 0)
			(type default)
		)
	)
	(wire
		(pts
			(xy 182.88 140.97) (xy 180.34 143.51)
		)
		(stroke
			(width 0)
			(type default)
		)
	)
	(wire
		(pts
			(xy 200.66 101.6) (xy 182.88 101.6)
		)
		(stroke
			(width 0)
			(type default)
		)
	)
	(wire
		(pts
			(xy 182.88 120.65) (xy 200.66 120.65)
		)
		(stroke
			(width 0)
			(type default)
		)
	)
	(wire
		(pts
			(xy 200.66 133.35) (xy 182.88 133.35)
		)
		(stroke
			(width 0)
			(type default)
		)
	)
	(wire
		(pts
			(xy 180.34 125.73) (xy 182.88 128.27)
		)
		(stroke
			(width 0)
			(type default)
		)
	)
	(bus
		(pts
			(xy 156.21 119.38) (xy 156.21 124.46)
		)
		(stroke
			(width 0)
			(type default)
		)
	)
	(wire
		(pts
			(xy 182.88 133.35) (xy 180.34 135.89)
		)
		(stroke
			(width 0)
			(type default)
		)
	)
	(wire
		(pts
			(xy 182.88 118.11) (xy 180.34 120.65)
		)
		(stroke
			(width 0)
			(type default)
		)
	)
	(wire
		(pts
			(xy 209.55 198.12) (xy 209.55 200.66)
		)
		(stroke
			(width 0)
			(type default)
		)
	)
	(wire
		(pts
			(xy 267.97 85.09) (xy 267.97 86.36)
		)
		(stroke
			(width 0)
			(type default)
		)
	)
	(wire
		(pts
			(xy 267.97 81.28) (xy 267.97 85.09)
		)
		(stroke
			(width 0)
			(type default)
		)
	)
	(wire
		(pts
			(xy 180.34 118.11) (xy 182.88 120.65)
		)
		(stroke
			(width 0)
			(type default)
		)
	)
	(wire
		(pts
			(xy 267.97 92.71) (xy 267.97 91.44)
		)
		(stroke
			(width 0)
			(type default)
		)
	)
	(wire
		(pts
			(xy 232.41 166.37) (xy 232.41 163.83)
		)
		(stroke
			(width 0)
			(type default)
		)
	)
	(bus
		(pts
			(xy 156.21 124.46) (xy 156.21 127)
		)
		(stroke
			(width 0)
			(type default)
		)
	)
	(wire
		(pts
			(xy 193.04 81.28) (xy 184.15 81.28)
		)
		(stroke
			(width 0)
			(type default)
		)
	)
	(bus
		(pts
			(xy 156.21 147.32) (xy 156.21 149.86)
		)
		(stroke
			(width 0)
			(type default)
		)
	)
	(wire
		(pts
			(xy 182.88 143.51) (xy 200.66 143.51)
		)
		(stroke
			(width 0)
			(type default)
		)
	)
	(bus
		(pts
			(xy 156.21 139.7) (xy 156.21 142.24)
		)
		(stroke
			(width 0)
			(type default)
		)
	)
	(wire
		(pts
			(xy 184.15 81.28) (xy 184.15 82.55)
		)
		(stroke
			(width 0)
			(type default)
		)
	)
	(wire
		(pts
			(xy 231.14 166.37) (xy 232.41 166.37)
		)
		(stroke
			(width 0)
			(type default)
		)
	)
	(wire
		(pts
			(xy 257.81 85.09) (xy 247.65 85.09)
		)
		(stroke
			(width 0)
			(type default)
		)
	)
	(wire
		(pts
			(xy 237.49 85.09) (xy 237.49 86.36)
		)
		(stroke
			(width 0)
			(type default)
		)
	)
	(wire
		(pts
			(xy 257.81 85.09) (xy 257.81 86.36)
		)
		(stroke
			(width 0)
			(type default)
		)
	)
	(wire
		(pts
			(xy 200.66 163.83) (xy 182.88 163.83)
		)
		(stroke
			(width 0)
			(type default)
		)
	)
	(wire
		(pts
			(xy 182.88 148.59) (xy 180.34 151.13)
		)
		(stroke
			(width 0)
			(type default)
		)
	)
	(bus
		(pts
			(xy 156.21 157.48) (xy 156.21 162.56)
		)
		(stroke
			(width 0)
			(type default)
		)
	)
	(wire
		(pts
			(xy 232.41 167.64) (xy 232.41 166.37)
		)
		(stroke
			(width 0)
			(type default)
		)
	)
	(wire
		(pts
			(xy 184.15 80.01) (xy 184.15 81.28)
		)
		(stroke
			(width 0)
			(type default)
		)
	)
	(wire
		(pts
			(xy 182.88 156.21) (xy 180.34 158.75)
		)
		(stroke
			(width 0)
			(type default)
		)
	)
	(wire
		(pts
			(xy 209.55 198.12) (xy 210.82 198.12)
		)
		(stroke
			(width 0)
			(type default)
		)
	)
	(wire
		(pts
			(xy 267.97 85.09) (xy 257.81 85.09)
		)
		(stroke
			(width 0)
			(type default)
		)
	)
	(bus
		(pts
			(xy 156.21 109.22) (xy 156.21 111.76)
		)
		(stroke
			(width 0)
			(type default)
		)
	)
	(wire
		(pts
			(xy 182.88 128.27) (xy 200.66 128.27)
		)
		(stroke
			(width 0)
			(type default)
		)
	)
	(wire
		(pts
			(xy 157.48 158.75) (xy 180.34 158.75)
		)
		(stroke
			(width 0)
			(type default)
		)
	)
	(wire
		(pts
			(xy 157.48 120.65) (xy 180.34 120.65)
		)
		(stroke
			(width 0)
			(type default)
		)
	)
	(wire
		(pts
			(xy 157.48 133.35) (xy 180.34 133.35)
		)
		(stroke
			(width 0)
			(type default)
		)
	)
	(bus
		(pts
			(xy 156.21 154.94) (xy 156.21 157.48)
		)
		(stroke
			(width 0)
			(type default)
		)
	)
	(wire
		(pts
			(xy 237.49 92.71) (xy 237.49 91.44)
		)
		(stroke
			(width 0)
			(type default)
		)
	)
	(wire
		(pts
			(xy 149.86 91.44) (xy 193.04 91.44)
		)
		(stroke
			(width 0)
			(type default)
		)
	)
	(wire
		(pts
			(xy 157.48 135.89) (xy 180.34 135.89)
		)
		(stroke
			(width 0)
			(type default)
		)
	)
	(wire
		(pts
			(xy 182.88 125.73) (xy 180.34 128.27)
		)
		(stroke
			(width 0)
			(type default)
		)
	)
	(wire
		(pts
			(xy 182.88 110.49) (xy 180.34 113.03)
		)
		(stroke
			(width 0)
			(type default)
		)
	)
	(bus
		(pts
			(xy 156.21 134.62) (xy 156.21 139.7)
		)
		(stroke
			(width 0)
			(type default)
		)
	)
	(wire
		(pts
			(xy 247.65 85.09) (xy 247.65 86.36)
		)
		(stroke
			(width 0)
			(type default)
		)
	)
	(wire
		(pts
			(xy 182.88 151.13) (xy 200.66 151.13)
		)
		(stroke
			(width 0)
			(type default)
		)
	)
	(bus
		(pts
			(xy 149.86 83.82) (xy 154.94 83.82)
		)
		(stroke
			(width 0)
			(type default)
		)
	)
	(wire
		(pts
			(xy 231.14 88.9) (xy 232.41 88.9)
		)
		(stroke
			(width 0)
			(type default)
		)
	)
	(wire
		(pts
			(xy 257.81 92.71) (xy 257.81 91.44)
		)
		(stroke
			(width 0)
			(type default)
		)
	)
	(wire
		(pts
			(xy 267.97 74.93) (xy 267.97 76.2)
		)
		(stroke
			(width 0)
			(type default)
		)
	)
	(wire
		(pts
			(xy 157.48 118.11) (xy 180.34 118.11)
		)
		(stroke
			(width 0)
			(type default)
		)
	)
	(wire
		(pts
			(xy 184.15 88.9) (xy 200.66 88.9)
		)
		(stroke
			(width 0)
			(type default)
		)
	)
	(wire
		(pts
			(xy 232.41 129.54) (xy 232.41 130.81)
		)
		(stroke
			(width 0)
			(type default)
		)
	)
	(wire
		(pts
			(xy 200.66 118.11) (xy 182.88 118.11)
		)
		(stroke
			(width 0)
			(type default)
		)
	)
	(wire
		(pts
			(xy 200.66 148.59) (xy 182.88 148.59)
		)
		(stroke
			(width 0)
			(type default)
		)
	)
	(wire
		(pts
			(xy 157.48 151.13) (xy 180.34 151.13)
		)
		(stroke
			(width 0)
			(type default)
		)
	)
	(wire
		(pts
			(xy 157.48 143.51) (xy 180.34 143.51)
		)
		(stroke
			(width 0)
			(type default)
		)
	)
	(wire
		(pts
			(xy 180.34 163.83) (xy 182.88 166.37)
		)
		(stroke
			(width 0)
			(type default)
		)
	)
	(wire
		(pts
			(xy 149.86 88.9) (xy 162.56 88.9)
		)
		(stroke
			(width 0)
			(type default)
		)
	)
	(wire
		(pts
			(xy 182.88 135.89) (xy 200.66 135.89)
		)
		(stroke
			(width 0)
			(type default)
		)
	)
	(wire
		(pts
			(xy 200.66 110.49) (xy 182.88 110.49)
		)
		(stroke
			(width 0)
			(type default)
		)
	)
	(wire
		(pts
			(xy 157.48 110.49) (xy 180.34 110.49)
		)
		(stroke
			(width 0)
			(type default)
		)
	)
	(bus
		(pts
			(xy 156.21 149.86) (xy 156.21 154.94)
		)
		(stroke
			(width 0)
			(type default)
		)
	)
	(wire
		(pts
			(xy 200.66 156.21) (xy 182.88 156.21)
		)
		(stroke
			(width 0)
			(type default)
		)
	)
	(bus
		(pts
			(xy 156.21 127) (xy 156.21 132.08)
		)
		(stroke
			(width 0)
			(type default)
		)
	)
	(wire
		(pts
			(xy 184.15 87.63) (xy 184.15 88.9)
		)
		(stroke
			(width 0)
			(type default)
		)
	)
	(wire
		(pts
			(xy 193.04 87.63) (xy 193.04 91.44)
		)
		(stroke
			(width 0)
			(type default)
		)
	)
	(wire
		(pts
			(xy 232.41 85.09) (xy 237.49 85.09)
		)
		(stroke
			(width 0)
			(type default)
		)
	)
	(wire
		(pts
			(xy 193.04 81.28) (xy 193.04 82.55)
		)
		(stroke
			(width 0)
			(type default)
		)
	)
	(bus
		(pts
			(xy 156.21 85.09) (xy 156.21 109.22)
		)
		(stroke
			(width 0)
			(type default)
		)
	)
	(wire
		(pts
			(xy 157.48 125.73) (xy 180.34 125.73)
		)
		(stroke
			(width 0)
			(type default)
		)
	)
	(bus
		(pts
			(xy 156.21 111.76) (xy 156.21 116.84)
		)
		(stroke
			(width 0)
			(type default)
		)
	)
	(wire
		(pts
			(xy 157.48 148.59) (xy 180.34 148.59)
		)
		(stroke
			(width 0)
			(type default)
		)
	)
	(wire
		(pts
			(xy 231.14 143.51) (xy 232.41 143.51)
		)
		(stroke
			(width 0)
			(type default)
		)
	)
	(wire
		(pts
			(xy 157.48 140.97) (xy 180.34 140.97)
		)
		(stroke
			(width 0)
			(type default)
		)
	)
	(wire
		(pts
			(xy 232.41 135.89) (xy 232.41 137.16)
		)
		(stroke
			(width 0)
			(type default)
		)
	)
	(wire
		(pts
			(xy 157.48 163.83) (xy 180.34 163.83)
		)
		(stroke
			(width 0)
			(type default)
		)
	)
	(wire
		(pts
			(xy 157.48 128.27) (xy 180.34 128.27)
		)
		(stroke
			(width 0)
			(type default)
		)
	)
	(wire
		(pts
			(xy 231.14 101.6) (xy 236.22 101.6)
		)
		(stroke
			(width 0)
			(type default)
		)
	)
	(bus
		(pts
			(xy 156.21 162.56) (xy 156.21 165.1)
		)
		(stroke
			(width 0)
			(type default)
		)
	)
	(wire
		(pts
			(xy 232.41 142.24) (xy 232.41 143.51)
		)
		(stroke
			(width 0)
			(type default)
		)
	)
	(wire
		(pts
			(xy 180.34 148.59) (xy 182.88 151.13)
		)
		(stroke
			(width 0)
			(type default)
		)
	)
	(wire
		(pts
			(xy 232.41 163.83) (xy 231.14 163.83)
		)
		(stroke
			(width 0)
			(type default)
		)
	)
	(bus
		(pts
			(xy 181.61 97.79) (xy 180.34 96.52)
		)
		(stroke
			(width 0)
			(type default)
		)
	)
	(bus
		(pts
			(xy 181.61 102.87) (xy 181.61 100.33)
		)
		(stroke
			(width 0)
			(type default)
		)
	)
	(wire
		(pts
			(xy 180.34 156.21) (xy 182.88 158.75)
		)
		(stroke
			(width 0)
			(type default)
		)
	)
	(wire
		(pts
			(xy 182.88 113.03) (xy 200.66 113.03)
		)
		(stroke
			(width 0)
			(type default)
		)
	)
	(wire
		(pts
			(xy 180.34 140.97) (xy 182.88 143.51)
		)
		(stroke
			(width 0)
			(type default)
		)
	)
	(wire
		(pts
			(xy 200.66 125.73) (xy 182.88 125.73)
		)
		(stroke
			(width 0)
			(type default)
		)
	)
	(wire
		(pts
			(xy 167.64 88.9) (xy 184.15 88.9)
		)
		(stroke
			(width 0)
			(type default)
		)
	)
	(wire
		(pts
			(xy 180.34 133.35) (xy 182.88 135.89)
		)
		(stroke
			(width 0)
			(type default)
		)
	)
	(bus
		(pts
			(xy 156.21 116.84) (xy 156.21 119.38)
		)
		(stroke
			(width 0)
			(type default)
		)
	)
	(bus
		(pts
			(xy 156.21 142.24) (xy 156.21 147.32)
		)
		(stroke
			(width 0)
			(type default)
		)
	)
	(wire
		(pts
			(xy 182.88 158.75) (xy 200.66 158.75)
		)
		(stroke
			(width 0)
			(type default)
		)
	)
	(label "PCIe_{x4}.TX2-"
		(at 158.75 143.51 0)
		(effects
			(font
				(size 1.27 1.27)
			)
			(justify left bottom)
		)
	)
	(label "PCIe_{x4}.TX1-"
		(at 158.75 128.27 0)
		(effects
			(font
				(size 1.27 1.27)
			)
			(justify left bottom)
		)
	)
	(label "PCIe_{x4}.TX1+"
		(at 158.75 125.73 0)
		(effects
			(font
				(size 1.27 1.27)
			)
			(justify left bottom)
		)
	)
	(label "PCIe_{x4}.RX2+"
		(at 158.75 148.59 0)
		(effects
			(font
				(size 1.27 1.27)
			)
			(justify left bottom)
		)
	)
	(label "PCIe_{x4}.TX2+"
		(at 158.75 140.97 0)
		(effects
			(font
				(size 1.27 1.27)
			)
			(justify left bottom)
		)
	)
	(label "PCIe_{x4}.RX1-"
		(at 158.75 135.89 0)
		(effects
			(font
				(size 1.27 1.27)
			)
			(justify left bottom)
		)
	)
	(label "PCIe_{x4}.RX0+"
		(at 158.75 118.11 0)
		(effects
			(font
				(size 1.27 1.27)
			)
			(justify left bottom)
		)
	)
	(label "M2_3V3"
		(at 232.41 85.09 0)
		(effects
			(font
				(size 1.27 1.27)
			)
			(justify left bottom)
		)
	)
	(label "PCIe_{x4}.RX0-"
		(at 158.75 120.65 0)
		(effects
			(font
				(size 1.27 1.27)
			)
			(justify left bottom)
		)
	)
	(label "PCIE_{REF}.CK+"
		(at 200.66 101.6 180)
		(effects
			(font
				(size 1.27 1.27)
			)
			(justify right bottom)
		)
	)
	(label "PCIe_{x4}.TX0-"
		(at 158.75 113.03 0)
		(effects
			(font
				(size 1.27 1.27)
			)
			(justify left bottom)
		)
	)
	(label "PCIe_{x4}.RX3-"
		(at 158.75 166.37 0)
		(effects
			(font
				(size 1.27 1.27)
			)
			(justify left bottom)
		)
	)
	(label "PCIe_{x4}.TX3+"
		(at 158.75 156.21 0)
		(effects
			(font
				(size 1.27 1.27)
			)
			(justify left bottom)
		)
	)
	(label "PCIe_{x4}.RX2-"
		(at 158.75 151.13 0)
		(effects
			(font
				(size 1.27 1.27)
			)
			(justify left bottom)
		)
	)
	(label "PCIe_{x4}.TX0+"
		(at 158.75 110.49 0)
		(effects
			(font
				(size 1.27 1.27)
			)
			(justify left bottom)
		)
	)
	(label "~{PERST_D}"
		(at 171.45 88.9 0)
		(effects
			(font
				(size 1.27 1.27)
			)
			(justify left bottom)
		)
	)
	(label "PCIe_{x4}.TX3-"
		(at 158.75 158.75 0)
		(effects
			(font
				(size 1.27 1.27)
			)
			(justify left bottom)
		)
	)
	(label "PCIE_{REF}.CK-"
		(at 200.66 104.14 180)
		(effects
			(font
				(size 1.27 1.27)
			)
			(justify right bottom)
		)
	)
	(label "PCIe_{x4}.RX1+"
		(at 158.75 133.35 0)
		(effects
			(font
				(size 1.27 1.27)
			)
			(justify left bottom)
		)
	)
	(label "PCIe_{x4}.RX3+"
		(at 158.75 163.83 0)
		(effects
			(font
				(size 1.27 1.27)
			)
			(justify left bottom)
		)
	)
	(hierarchical_label "~{PERST}"
		(shape input)
		(at 149.86 88.9 180)
		(effects
			(font
				(size 1.27 1.27)
			)
			(justify right)
		)
	)
	(hierarchical_label "SUSCLK"
		(shape input)
		(at 246.38 101.6 0)
		(effects
			(font
				(size 1.27 1.27)
			)
			(justify left)
		)
	)
	(hierarchical_label "PCIE_{REF}{PCIe_{REF}}"
		(shape input)
		(at 149.86 96.52 180)
		(effects
			(font
				(size 1.27 1.27)
			)
			(justify right)
		)
	)
	(hierarchical_label "PCIe_{x4}{PCIe}"
		(shape input)
		(at 149.86 83.82 180)
		(effects
			(font
				(size 1.27 1.27)
			)
			(justify right)
		)
	)
	(hierarchical_label "~{CLKREQ}"
		(shape output)
		(at 149.86 91.44 180)
		(effects
			(font
				(size 1.27 1.27)
			)
			(justify right)
		)
	)
	(symbol
		(lib_id "antmicroResistors0402:R_0R_0402")
		(at 162.56 88.9 0)
		(unit 1)
		(exclude_from_sim no)
		(in_bom yes)
		(on_board yes)
		(dnp no)
		(property "Reference" "R126"
			(at 160.02 87.63 0)
			(effects
				(font
					(size 1.27 1.27)
					(thickness 0.15)
				)
			)
		)
		(property "Value" "R_0R_0402"
			(at 182.88 101.6 0)
			(effects
				(font
					(size 1.27 1.27)
					(thickness 0.15)
				)
				(justify left bottom)
				(hide yes)
			)
		)
		(property "Footprint" "antmicro-footprints:R_0402_1005Metric"
			(at 182.88 104.14 0)
			(effects
				(font
					(size 1.27 1.27)
					(thickness 0.15)
				)
				(justify left bottom)
				(hide yes)
			)
		)
		(property "Datasheet" "https://industrial.panasonic.com/cdbs/www-data/pdf/RDA0000/AOA0000C301.pdf"
			(at 182.88 106.68 0)
			(effects
				(font
					(size 1.27 1.27)
					(thickness 0.15)
				)
				(justify left bottom)
				(hide yes)
			)
		)
		(property "Description" ""
			(at 162.56 88.9 0)
			(effects
				(font
					(size 1.27 1.27)
				)
				(hide yes)
			)
		)
		(property "MPN" "ERJ2GE0R00X"
			(at 182.88 109.22 0)
			(effects
				(font
					(size 1.27 1.27)
					(thickness 0.15)
				)
				(justify left bottom)
				(hide yes)
			)
		)
		(property "Manufacturer" "Panasonic"
			(at 182.88 111.76 0)
			(effects
				(font
					(size 1.27 1.27)
					(thickness 0.15)
				)
				(justify left bottom)
				(hide yes)
			)
		)
		(property "License" "Apache-2.0"
			(at 182.88 114.3 0)
			(effects
				(font
					(size 1.27 1.27)
					(thickness 0.15)
				)
				(justify left bottom)
				(hide yes)
			)
		)
		(property "Author" "Antmicro"
			(at 182.88 116.84 0)
			(effects
				(font
					(size 1.27 1.27)
					(thickness 0.15)
				)
				(justify left bottom)
				(hide yes)
			)
		)
		(property "Val" "0R"
			(at 168.91 87.63 0)
			(effects
				(font
					(size 1.27 1.27)
					(thickness 0.15)
				)
			)
		)
		(property "Tolerance" "~"
			(at 182.88 99.06 0)
			(effects
				(font
					(size 1.27 1.27)
				)
				(justify left bottom)
				(hide yes)
			)
		)
		(property "Current" "1A"
			(at 182.88 119.38 0)
			(effects
				(font
					(size 1.27 1.27)
					(thickness 0.15)
				)
				(justify left bottom)
				(hide yes)
			)
		)
		(property "Public" "False"
			(at 182.88 119.38 0)
			(effects
				(font
					(size 1.27 1.27)
				)
				(justify left bottom)
				(hide yes)
			)
		)
		(pin "1"
		)
		(pin "2"
		)
		(instances
			(project "com-express-7-baseboard"
				(path ""
					(reference "R126")
					(unit 1)
				)
			)
		)
	)
	(symbol
		(lib_id "antmicropower:+3V3")
		(at 232.41 129.54 0)
		(unit 1)
		(exclude_from_sim no)
		(in_bom yes)
		(on_board yes)
		(dnp no)
		(property "Reference" "#PWR0167"
			(at 232.41 133.35 0)
			(effects
				(font
					(size 1.27 1.27)
				)
				(justify left bottom)
				(hide yes)
			)
		)
		(property "Value" "+3V3"
			(at 229.87 125.73 0)
			(effects
				(font
					(size 1.27 1.27)
				)
				(justify left)
			)
		)
		(property "Footprint" ""
			(at 232.41 129.54 0)
			(effects
				(font
					(size 1.27 1.27)
				)
				(justify left bottom)
				(hide yes)
			)
		)
		(property "Datasheet" ""
			(at 232.41 129.54 0)
			(effects
				(font
					(size 1.27 1.27)
				)
				(justify left bottom)
				(hide yes)
			)
		)
		(property "Description" ""
			(at 232.41 129.54 0)
			(effects
				(font
					(size 1.27 1.27)
				)
				(hide yes)
			)
		)
		(property "Author" "Antmicro"
			(at 247.65 132.08 0)
			(effects
				(font
					(size 1.27 1.27)
					(thickness 0.15)
				)
				(justify left bottom)
				(hide yes)
			)
		)
		(property "License" "Apache-2.0"
			(at 247.65 134.62 0)
			(effects
				(font
					(size 1.27 1.27)
					(thickness 0.15)
				)
				(justify left bottom)
				(hide yes)
			)
		)
		(pin "1"
		)
		(instances
			(project "com-express-7-baseboard"
				(path ""
					(reference "#PWR0167")
					(unit 1)
				)
			)
		)
	)
	(symbol
		(lib_id "antmicroCapacitors0603:C_22u_16V_0603")
		(at 267.97 91.44 90)
		(unit 1)
		(exclude_from_sim no)
		(in_bom yes)
		(on_board yes)
		(dnp no)
		(fields_autoplaced yes)
		(property "Reference" "C78"
			(at 270.51 87.6235 90)
			(effects
				(font
					(size 1.27 1.27)
					(thickness 0.15)
				)
				(justify right)
			)
		)
		(property "Value" "C_22u_16V_0603"
			(at 278.13 71.12 0)
			(effects
				(font
					(size 1.27 1.27)
					(thickness 0.15)
				)
				(justify left bottom)
				(hide yes)
			)
		)
		(property "Footprint" "antmicro-footprints:C_0603_1608Metric"
			(at 280.67 71.12 0)
			(effects
				(font
					(size 1.27 1.27)
					(thickness 0.15)
				)
				(justify left bottom)
				(hide yes)
			)
		)
		(property "Datasheet" "https://product.samsungsem.com/mlcc/CL10A226MO7JZN.do"
			(at 283.21 71.12 0)
			(effects
				(font
					(size 1.27 1.27)
					(thickness 0.15)
				)
				(justify left bottom)
				(hide yes)
			)
		)
		(property "Description" ""
			(at 267.97 91.44 0)
			(effects
				(font
					(size 1.27 1.27)
				)
				(hide yes)
			)
		)
		(property "MPN" "CL10A226MO7JZNC"
			(at 285.75 71.12 0)
			(effects
				(font
					(size 1.27 1.27)
					(thickness 0.15)
				)
				(justify left bottom)
				(hide yes)
			)
		)
		(property "Manufacturer" "Samsung Electro-Mechanics"
			(at 288.29 71.12 0)
			(effects
				(font
					(size 1.27 1.27)
					(thickness 0.15)
				)
				(justify left bottom)
				(hide yes)
			)
		)
		(property "License" "Apache-2.0"
			(at 290.83 71.12 0)
			(effects
				(font
					(size 1.27 1.27)
					(thickness 0.15)
				)
				(justify left bottom)
				(hide yes)
			)
		)
		(property "Author" "Antmicro"
			(at 293.37 71.12 0)
			(effects
				(font
					(size 1.27 1.27)
					(thickness 0.15)
				)
				(justify left bottom)
				(hide yes)
			)
		)
		(property "Val" "22u"
			(at 270.51 90.1635 90)
			(effects
				(font
					(size 1.27 1.27)
					(thickness 0.15)
				)
				(justify right)
			)
		)
		(property "Voltage" "16V"
			(at 295.91 71.12 0)
			(effects
				(font
					(size 1.27 1.27)
				)
				(justify left bottom)
				(hide yes)
			)
		)
		(property "Dielectric" ""
			(at 298.45 71.12 0)
			(effects
				(font
					(size 1.27 1.27)
				)
				(justify left bottom)
				(hide yes)
			)
		)
		(property "Public" "False"
			(at 300.99 71.12 0)
			(effects
				(font
					(size 1.27 1.27)
				)
				(justify left bottom)
				(hide yes)
			)
		)
		(pin "2"
		)
		(pin "1"
		)
		(instances
			(project "com-express-7-baseboard"
				(path ""
					(reference "C78")
					(unit 1)
				)
			)
		)
	)
	(symbol
		(lib_id "antmicropower:GND")
		(at 209.55 200.66 0)
		(unit 1)
		(exclude_from_sim no)
		(in_bom yes)
		(on_board yes)
		(dnp no)
		(property "Reference" "#PWR0157"
			(at 209.55 207.01 0)
			(effects
				(font
					(size 1.27 1.27)
				)
				(justify left bottom)
				(hide yes)
			)
		)
		(property "Value" "GND"
			(at 207.645 205.74 0)
			(effects
				(font
					(size 1.27 1.27)
				)
				(justify left bottom)
			)
		)
		(property "Footprint" ""
			(at 209.55 200.66 0)
			(effects
				(font
					(size 1.27 1.27)
				)
				(justify left bottom)
				(hide yes)
			)
		)
		(property "Datasheet" ""
			(at 209.55 200.66 0)
			(effects
				(font
					(size 1.27 1.27)
				)
				(justify left bottom)
				(hide yes)
			)
		)
		(property "Description" ""
			(at 209.55 200.66 0)
			(effects
				(font
					(size 1.27 1.27)
				)
				(hide yes)
			)
		)
		(property "Author" "Antmicro"
			(at 218.44 208.28 0)
			(effects
				(font
					(size 1.27 1.27)
					(thickness 0.15)
				)
				(justify left bottom)
				(hide yes)
			)
		)
		(property "License" "Apache-2.0"
			(at 218.44 210.82 0)
			(effects
				(font
					(size 1.27 1.27)
					(thickness 0.15)
				)
				(justify left bottom)
				(hide yes)
			)
		)
		(pin "1"
		)
		(instances
			(project "com-express-7-baseboard"
				(path ""
					(reference "#PWR0157")
					(unit 1)
				)
			)
		)
	)
	(symbol
		(lib_id "antmicroCapacitors0603:C_22u_16V_0603")
		(at 257.81 91.44 90)
		(unit 1)
		(exclude_from_sim no)
		(in_bom yes)
		(on_board yes)
		(dnp no)
		(fields_autoplaced yes)
		(property "Reference" "C77"
			(at 260.35 87.6235 90)
			(effects
				(font
					(size 1.27 1.27)
					(thickness 0.15)
				)
				(justify right)
			)
		)
		(property "Value" "C_22u_16V_0603"
			(at 267.97 71.12 0)
			(effects
				(font
					(size 1.27 1.27)
					(thickness 0.15)
				)
				(justify left bottom)
				(hide yes)
			)
		)
		(property "Footprint" "antmicro-footprints:C_0603_1608Metric"
			(at 270.51 71.12 0)
			(effects
				(font
					(size 1.27 1.27)
					(thickness 0.15)
				)
				(justify left bottom)
				(hide yes)
			)
		)
		(property "Datasheet" "https://product.samsungsem.com/mlcc/CL10A226MO7JZN.do"
			(at 273.05 71.12 0)
			(effects
				(font
					(size 1.27 1.27)
					(thickness 0.15)
				)
				(justify left bottom)
				(hide yes)
			)
		)
		(property "Description" ""
			(at 257.81 91.44 0)
			(effects
				(font
					(size 1.27 1.27)
				)
				(hide yes)
			)
		)
		(property "MPN" "CL10A226MO7JZNC"
			(at 275.59 71.12 0)
			(effects
				(font
					(size 1.27 1.27)
					(thickness 0.15)
				)
				(justify left bottom)
				(hide yes)
			)
		)
		(property "Manufacturer" "Samsung Electro-Mechanics"
			(at 278.13 71.12 0)
			(effects
				(font
					(size 1.27 1.27)
					(thickness 0.15)
				)
				(justify left bottom)
				(hide yes)
			)
		)
		(property "License" "Apache-2.0"
			(at 280.67 71.12 0)
			(effects
				(font
					(size 1.27 1.27)
					(thickness 0.15)
				)
				(justify left bottom)
				(hide yes)
			)
		)
		(property "Author" "Antmicro"
			(at 283.21 71.12 0)
			(effects
				(font
					(size 1.27 1.27)
					(thickness 0.15)
				)
				(justify left bottom)
				(hide yes)
			)
		)
		(property "Val" "22u"
			(at 260.35 90.1635 90)
			(effects
				(font
					(size 1.27 1.27)
					(thickness 0.15)
				)
				(justify right)
			)
		)
		(property "Voltage" "16V"
			(at 285.75 71.12 0)
			(effects
				(font
					(size 1.27 1.27)
				)
				(justify left bottom)
				(hide yes)
			)
		)
		(property "Dielectric" ""
			(at 288.29 71.12 0)
			(effects
				(font
					(size 1.27 1.27)
				)
				(justify left bottom)
				(hide yes)
			)
		)
		(property "Public" "False"
			(at 290.83 71.12 0)
			(effects
				(font
					(size 1.27 1.27)
				)
				(justify left bottom)
				(hide yes)
			)
		)
		(pin "2"
		)
		(pin "1"
		)
		(instances
			(project "com-express-7-baseboard"
				(path ""
					(reference "C77")
					(unit 1)
				)
			)
		)
	)
	(symbol
		(lib_id "antmicroResistors0402:R_10k_0402")
		(at 193.04 87.63 90)
		(unit 1)
		(exclude_from_sim no)
		(in_bom yes)
		(on_board yes)
		(dnp no)
		(fields_autoplaced yes)
		(property "Reference" "R128"
			(at 195.58 82.55 90)
			(effects
				(font
					(size 1.27 1.27)
					(thickness 0.15)
				)
				(justify right)
			)
		)
		(property "Value" "R_10k_0402"
			(at 205.74 67.31 0)
			(effects
				(font
					(size 1.27 1.27)
					(thickness 0.15)
				)
				(justify left bottom)
				(hide yes)
			)
		)
		(property "Footprint" "antmicro-footprints:R_0402_1005Metric"
			(at 208.28 67.31 0)
			(effects
				(font
					(size 1.27 1.27)
					(thickness 0.15)
				)
				(justify left bottom)
				(hide yes)
			)
		)
		(property "Datasheet" "https://www.bourns.com/docs/product-datasheets/cr.pdf"
			(at 210.82 67.31 0)
			(effects
				(font
					(size 1.27 1.27)
					(thickness 0.15)
				)
				(justify left bottom)
				(hide yes)
			)
		)
		(property "Description" ""
			(at 193.04 87.63 0)
			(effects
				(font
					(size 1.27 1.27)
				)
				(hide yes)
			)
		)
		(property "MPN" "CR0402-FX-1002GLF"
			(at 213.36 67.31 0)
			(effects
				(font
					(size 1.27 1.27)
					(thickness 0.15)
				)
				(justify left bottom)
				(hide yes)
			)
		)
		(property "Manufacturer" "Bourns"
			(at 215.9 67.31 0)
			(effects
				(font
					(size 1.27 1.27)
					(thickness 0.15)
				)
				(justify left bottom)
				(hide yes)
			)
		)
		(property "License" "Apache-2.0"
			(at 218.44 67.31 0)
			(effects
				(font
					(size 1.27 1.27)
					(thickness 0.15)
				)
				(justify left bottom)
				(hide yes)
			)
		)
		(property "Author" "Antmicro"
			(at 220.98 67.31 0)
			(effects
				(font
					(size 1.27 1.27)
					(thickness 0.15)
				)
				(justify left bottom)
				(hide yes)
			)
		)
		(property "Val" "10k"
			(at 195.58 85.09 90)
			(effects
				(font
					(size 1.27 1.27)
					(thickness 0.15)
				)
				(justify right)
			)
		)
		(property "Tolerance" "1%"
			(at 203.2 67.31 0)
			(effects
				(font
					(size 1.27 1.27)
				)
				(justify left bottom)
				(hide yes)
			)
		)
		(property "Public" "False"
			(at 223.52 67.31 0)
			(effects
				(font
					(size 1.27 1.27)
				)
				(justify left bottom)
				(hide yes)
			)
		)
		(pin "2"
		)
		(pin "1"
		)
		(instances
			(project "com-express-7-baseboard"
				(path ""
					(reference "R128")
					(unit 1)
				)
			)
		)
	)
	(symbol
		(lib_id "antmicropower:+3V3")
		(at 267.97 74.93 0)
		(unit 1)
		(exclude_from_sim no)
		(in_bom yes)
		(on_board yes)
		(dnp no)
		(property "Reference" "#PWR0172"
			(at 267.97 78.74 0)
			(effects
				(font
					(size 1.27 1.27)
				)
				(justify left bottom)
				(hide yes)
			)
		)
		(property "Value" "+3V3"
			(at 265.43 71.12 0)
			(effects
				(font
					(size 1.27 1.27)
				)
				(justify left)
			)
		)
		(property "Footprint" ""
			(at 267.97 74.93 0)
			(effects
				(font
					(size 1.27 1.27)
				)
				(justify left bottom)
				(hide yes)
			)
		)
		(property "Datasheet" ""
			(at 267.97 74.93 0)
			(effects
				(font
					(size 1.27 1.27)
				)
				(justify left bottom)
				(hide yes)
			)
		)
		(property "Description" ""
			(at 267.97 74.93 0)
			(effects
				(font
					(size 1.27 1.27)
				)
				(hide yes)
			)
		)
		(property "Author" "Antmicro"
			(at 283.21 77.47 0)
			(effects
				(font
					(size 1.27 1.27)
					(thickness 0.15)
				)
				(justify left bottom)
				(hide yes)
			)
		)
		(property "License" "Apache-2.0"
			(at 283.21 80.01 0)
			(effects
				(font
					(size 1.27 1.27)
					(thickness 0.15)
				)
				(justify left bottom)
				(hide yes)
			)
		)
		(pin "1"
		)
		(instances
			(project "com-express-7-baseboard"
				(path ""
					(reference "#PWR0172")
					(unit 1)
				)
			)
		)
	)
	(symbol
		(lib_id "antmicropower:GND")
		(at 267.97 92.71 0)
		(unit 1)
		(exclude_from_sim no)
		(in_bom yes)
		(on_board yes)
		(dnp no)
		(property "Reference" "#PWR0173"
			(at 267.97 99.06 0)
			(effects
				(font
					(size 1.27 1.27)
				)
				(justify left bottom)
				(hide yes)
			)
		)
		(property "Value" "GND"
			(at 266.065 97.79 0)
			(effects
				(font
					(size 1.27 1.27)
				)
				(justify left bottom)
			)
		)
		(property "Footprint" ""
			(at 267.97 92.71 0)
			(effects
				(font
					(size 1.27 1.27)
				)
				(justify left bottom)
				(hide yes)
			)
		)
		(property "Datasheet" ""
			(at 267.97 92.71 0)
			(effects
				(font
					(size 1.27 1.27)
				)
				(justify left bottom)
				(hide yes)
			)
		)
		(property "Description" ""
			(at 267.97 92.71 0)
			(effects
				(font
					(size 1.27 1.27)
				)
				(hide yes)
			)
		)
		(property "Author" "Antmicro"
			(at 276.86 100.33 0)
			(effects
				(font
					(size 1.27 1.27)
					(thickness 0.15)
				)
				(justify left bottom)
				(hide yes)
			)
		)
		(property "License" "Apache-2.0"
			(at 276.86 102.87 0)
			(effects
				(font
					(size 1.27 1.27)
					(thickness 0.15)
				)
				(justify left bottom)
				(hide yes)
			)
		)
		(pin "1"
		)
		(instances
			(project "com-express-7-baseboard"
				(path ""
					(reference "#PWR0173")
					(unit 1)
				)
			)
		)
	)
	(symbol
		(lib_id "antmicroMechanicalParts:Spacer_Drill3.7mm_H2.5mm_9774025151R")
		(at 210.82 198.12 0)
		(mirror x)
		(unit 1)
		(exclude_from_sim no)
		(in_bom yes)
		(on_board yes)
		(dnp no)
		(property "Reference" "H1"
			(at 220.98 196.85 0)
			(effects
				(font
					(size 1.27 1.27)
					(thickness 0.15)
				)
			)
		)
		(property "Value" "Spacer_Drill3.7mm_H2.5mm_9774025151R"
			(at 240.03 199.39 0)
			(effects
				(font
					(size 1.27 1.27)
					(thickness 0.15)
				)
			)
		)
		(property "Footprint" "antmicro-footprints:Spacer_Drill3.7mm_H2.5mm_9774025151R"
			(at 233.68 190.5 0)
			(effects
				(font
					(size 1.27 1.27)
					(thickness 0.15)
				)
				(justify left bottom)
				(hide yes)
			)
		)
		(property "Datasheet" "https://www.we-online.com/components/products/datasheet/9774025151R.pdf"
			(at 233.68 187.96 0)
			(effects
				(font
					(size 1.27 1.27)
					(thickness 0.15)
				)
				(justify left bottom)
				(hide yes)
			)
		)
		(property "Description" ""
			(at 210.82 198.12 0)
			(effects
				(font
					(size 1.27 1.27)
				)
				(hide yes)
			)
		)
		(property "Manufacturer" "Würth Elektronik"
			(at 233.68 185.42 0)
			(effects
				(font
					(size 1.27 1.27)
					(thickness 0.15)
				)
				(justify left bottom)
				(hide yes)
			)
		)
		(property "MPN" "9774025151R"
			(at 233.68 182.88 0)
			(effects
				(font
					(size 1.27 1.27)
					(thickness 0.15)
				)
				(justify left bottom)
				(hide yes)
			)
		)
		(property "Author" "Antmicro"
			(at 233.68 180.34 0)
			(effects
				(font
					(size 1.27 1.27)
					(thickness 0.15)
				)
				(justify left bottom)
				(hide yes)
			)
		)
		(property "License" "Apache-2.0"
			(at 233.68 177.8 0)
			(effects
				(font
					(size 1.27 1.27)
					(thickness 0.15)
				)
				(justify left bottom)
				(hide yes)
			)
		)
		(property "Public" "False"
			(at 233.68 185.42 0)
			(effects
				(font
					(size 1.27 1.27)
				)
				(justify left bottom)
				(hide yes)
			)
		)
		(pin "1"
		)
		(instances
			(project "com-express-7-baseboard"
				(path ""
					(reference "H1")
					(unit 1)
				)
			)
		)
	)
	(symbol
		(lib_id "antmicroResistors0402:R_0R_0402")
		(at 236.22 101.6 0)
		(unit 1)
		(exclude_from_sim no)
		(in_bom yes)
		(on_board yes)
		(dnp no)
		(property "Reference" "R130"
			(at 233.68 100.33 0)
			(effects
				(font
					(size 1.27 1.27)
					(thickness 0.15)
				)
			)
		)
		(property "Value" "R_0R_0402"
			(at 256.54 114.3 0)
			(effects
				(font
					(size 1.27 1.27)
					(thickness 0.15)
				)
				(justify left bottom)
				(hide yes)
			)
		)
		(property "Footprint" "antmicro-footprints:R_0402_1005Metric"
			(at 256.54 116.84 0)
			(effects
				(font
					(size 1.27 1.27)
					(thickness 0.15)
				)
				(justify left bottom)
				(hide yes)
			)
		)
		(property "Datasheet" "https://industrial.panasonic.com/cdbs/www-data/pdf/RDA0000/AOA0000C301.pdf"
			(at 256.54 119.38 0)
			(effects
				(font
					(size 1.27 1.27)
					(thickness 0.15)
				)
				(justify left bottom)
				(hide yes)
			)
		)
		(property "Description" ""
			(at 236.22 101.6 0)
			(effects
				(font
					(size 1.27 1.27)
				)
				(hide yes)
			)
		)
		(property "MPN" "ERJ2GE0R00X"
			(at 256.54 121.92 0)
			(effects
				(font
					(size 1.27 1.27)
					(thickness 0.15)
				)
				(justify left bottom)
				(hide yes)
			)
		)
		(property "Manufacturer" "Panasonic"
			(at 256.54 124.46 0)
			(effects
				(font
					(size 1.27 1.27)
					(thickness 0.15)
				)
				(justify left bottom)
				(hide yes)
			)
		)
		(property "License" "Apache-2.0"
			(at 256.54 127 0)
			(effects
				(font
					(size 1.27 1.27)
					(thickness 0.15)
				)
				(justify left bottom)
				(hide yes)
			)
		)
		(property "Author" "Antmicro"
			(at 256.54 129.54 0)
			(effects
				(font
					(size 1.27 1.27)
					(thickness 0.15)
				)
				(justify left bottom)
				(hide yes)
			)
		)
		(property "Val" "0R"
			(at 242.57 100.33 0)
			(effects
				(font
					(size 1.27 1.27)
					(thickness 0.15)
				)
			)
		)
		(property "Tolerance" "~"
			(at 256.54 111.76 0)
			(effects
				(font
					(size 1.27 1.27)
				)
				(justify left bottom)
				(hide yes)
			)
		)
		(property "Current" "1A"
			(at 256.54 132.08 0)
			(effects
				(font
					(size 1.27 1.27)
					(thickness 0.15)
				)
				(justify left bottom)
				(hide yes)
			)
		)
		(property "Public" "False"
			(at 256.54 132.08 0)
			(effects
				(font
					(size 1.27 1.27)
				)
				(justify left bottom)
				(hide yes)
			)
		)
		(pin "1"
		)
		(pin "2"
		)
		(instances
			(project "com-express-7-baseboard"
				(path ""
					(reference "R130")
					(unit 1)
				)
			)
		)
	)
	(symbol
		(lib_id "antmicroResistors0402:R_220R_0402")
		(at 232.41 135.89 90)
		(unit 1)
		(exclude_from_sim no)
		(in_bom yes)
		(on_board yes)
		(dnp no)
		(property "Reference" "R129"
			(at 233.68 132.08 90)
			(effects
				(font
					(size 1.27 1.27)
					(thickness 0.15)
				)
				(justify right)
			)
		)
		(property "Value" "R_220R_0402"
			(at 245.11 115.57 0)
			(effects
				(font
					(size 1.27 1.27)
					(thickness 0.15)
				)
				(justify left bottom)
				(hide yes)
			)
		)
		(property "Footprint" "antmicro-footprints:R_0402_1005Metric"
			(at 247.65 115.57 0)
			(effects
				(font
					(size 1.27 1.27)
					(thickness 0.15)
				)
				(justify left bottom)
				(hide yes)
			)
		)
		(property "Datasheet" "https://www.bourns.com/docs/product-datasheets/cr.pdf"
			(at 250.19 115.57 0)
			(effects
				(font
					(size 1.27 1.27)
					(thickness 0.15)
				)
				(justify left bottom)
				(hide yes)
			)
		)
		(property "Description" ""
			(at 232.41 135.89 0)
			(effects
				(font
					(size 1.27 1.27)
				)
				(hide yes)
			)
		)
		(property "MPN" "CR0402-FX-2200GLF"
			(at 252.73 115.57 0)
			(effects
				(font
					(size 1.27 1.27)
					(thickness 0.15)
				)
				(justify left bottom)
				(hide yes)
			)
		)
		(property "Manufacturer" "Bourns"
			(at 255.27 115.57 0)
			(effects
				(font
					(size 1.27 1.27)
					(thickness 0.15)
				)
				(justify left bottom)
				(hide yes)
			)
		)
		(property "License" "Apache-2.0"
			(at 257.81 115.57 0)
			(effects
				(font
					(size 1.27 1.27)
					(thickness 0.15)
				)
				(justify left bottom)
				(hide yes)
			)
		)
		(property "Author" "Antmicro"
			(at 260.35 115.57 0)
			(effects
				(font
					(size 1.27 1.27)
					(thickness 0.15)
				)
				(justify left bottom)
				(hide yes)
			)
		)
		(property "Val" "220R"
			(at 233.68 134.62 90)
			(effects
				(font
					(size 1.27 1.27)
					(thickness 0.15)
				)
				(justify right)
			)
		)
		(property "Tolerance" "1%"
			(at 242.57 115.57 0)
			(effects
				(font
					(size 1.27 1.27)
				)
				(justify left bottom)
				(hide yes)
			)
		)
		(property "Public" "False"
			(at 262.89 115.57 0)
			(effects
				(font
					(size 1.27 1.27)
				)
				(justify left bottom)
				(hide yes)
			)
		)
		(pin "2"
		)
		(pin "1"
		)
		(instances
			(project "com-express-7-baseboard"
				(path ""
					(reference "R129")
					(unit 1)
				)
			)
		)
	)
	(symbol
		(lib_id "antmicroResistors0402:R_10k_0402")
		(at 184.15 87.63 90)
		(unit 1)
		(exclude_from_sim no)
		(in_bom yes)
		(on_board yes)
		(dnp yes)
		(fields_autoplaced yes)
		(property "Reference" "R127"
			(at 186.69 82.55 90)
			(effects
				(font
					(size 1.27 1.27)
					(thickness 0.15)
				)
				(justify right)
			)
		)
		(property "Value" "R_10k_0402"
			(at 196.85 67.31 0)
			(effects
				(font
					(size 1.27 1.27)
					(thickness 0.15)
				)
				(justify left bottom)
				(hide yes)
			)
		)
		(property "Footprint" "antmicro-footprints:R_0402_1005Metric"
			(at 199.39 67.31 0)
			(effects
				(font
					(size 1.27 1.27)
					(thickness 0.15)
				)
				(justify left bottom)
				(hide yes)
			)
		)
		(property "Datasheet" "https://www.bourns.com/docs/product-datasheets/cr.pdf"
			(at 201.93 67.31 0)
			(effects
				(font
					(size 1.27 1.27)
					(thickness 0.15)
				)
				(justify left bottom)
				(hide yes)
			)
		)
		(property "Description" ""
			(at 184.15 87.63 0)
			(effects
				(font
					(size 1.27 1.27)
				)
				(hide yes)
			)
		)
		(property "MPN" "CR0402-FX-1002GLF"
			(at 204.47 67.31 0)
			(effects
				(font
					(size 1.27 1.27)
					(thickness 0.15)
				)
				(justify left bottom)
				(hide yes)
			)
		)
		(property "Manufacturer" "Bourns"
			(at 207.01 67.31 0)
			(effects
				(font
					(size 1.27 1.27)
					(thickness 0.15)
				)
				(justify left bottom)
				(hide yes)
			)
		)
		(property "License" "Apache-2.0"
			(at 209.55 67.31 0)
			(effects
				(font
					(size 1.27 1.27)
					(thickness 0.15)
				)
				(justify left bottom)
				(hide yes)
			)
		)
		(property "Author" "Antmicro"
			(at 212.09 67.31 0)
			(effects
				(font
					(size 1.27 1.27)
					(thickness 0.15)
				)
				(justify left bottom)
				(hide yes)
			)
		)
		(property "Val" "10k"
			(at 186.69 85.09 90)
			(effects
				(font
					(size 1.27 1.27)
					(thickness 0.15)
				)
				(justify right)
			)
		)
		(property "Tolerance" "1%"
			(at 194.31 67.31 0)
			(effects
				(font
					(size 1.27 1.27)
				)
				(justify left bottom)
				(hide yes)
			)
		)
		(property "Public" "False"
			(at 214.63 67.31 0)
			(effects
				(font
					(size 1.27 1.27)
				)
				(justify left bottom)
				(hide yes)
			)
		)
		(pin "2"
		)
		(pin "1"
		)
		(instances
			(project "com-express-7-baseboard"
				(path ""
					(reference "R127")
					(unit 1)
				)
			)
		)
	)
	(symbol
		(lib_id "antmicropower:GND")
		(at 237.49 92.71 0)
		(unit 1)
		(exclude_from_sim no)
		(in_bom yes)
		(on_board yes)
		(dnp no)
		(property "Reference" "#PWR0169"
			(at 237.49 99.06 0)
			(effects
				(font
					(size 1.27 1.27)
				)
				(justify left bottom)
				(hide yes)
			)
		)
		(property "Value" "GND"
			(at 235.585 97.79 0)
			(effects
				(font
					(size 1.27 1.27)
				)
				(justify left bottom)
			)
		)
		(property "Footprint" ""
			(at 237.49 92.71 0)
			(effects
				(font
					(size 1.27 1.27)
				)
				(justify left bottom)
				(hide yes)
			)
		)
		(property "Datasheet" ""
			(at 237.49 92.71 0)
			(effects
				(font
					(size 1.27 1.27)
				)
				(justify left bottom)
				(hide yes)
			)
		)
		(property "Description" ""
			(at 237.49 92.71 0)
			(effects
				(font
					(size 1.27 1.27)
				)
				(hide yes)
			)
		)
		(property "Author" "Antmicro"
			(at 246.38 100.33 0)
			(effects
				(font
					(size 1.27 1.27)
					(thickness 0.15)
				)
				(justify left bottom)
				(hide yes)
			)
		)
		(property "License" "Apache-2.0"
			(at 246.38 102.87 0)
			(effects
				(font
					(size 1.27 1.27)
					(thickness 0.15)
				)
				(justify left bottom)
				(hide yes)
			)
		)
		(pin "1"
		)
		(instances
			(project "com-express-7-baseboard"
				(path ""
					(reference "#PWR0169")
					(unit 1)
				)
			)
		)
	)
	(symbol
		(lib_id "antmicropower:+3V3")
		(at 184.15 80.01 0)
		(unit 1)
		(exclude_from_sim no)
		(in_bom yes)
		(on_board yes)
		(dnp no)
		(fields_autoplaced yes)
		(property "Reference" "#PWR0165"
			(at 184.15 83.82 0)
			(effects
				(font
					(size 1.27 1.27)
				)
				(justify left bottom)
				(hide yes)
			)
		)
		(property "Value" "+3V3"
			(at 184.15 76.454 0)
			(effects
				(font
					(size 1.27 1.27)
				)
				(justify left bottom)
			)
		)
		(property "Footprint" ""
			(at 184.15 80.01 0)
			(effects
				(font
					(size 1.27 1.27)
				)
				(justify left bottom)
				(hide yes)
			)
		)
		(property "Datasheet" ""
			(at 184.15 80.01 0)
			(effects
				(font
					(size 1.27 1.27)
				)
				(justify left bottom)
				(hide yes)
			)
		)
		(property "Description" ""
			(at 184.15 80.01 0)
			(effects
				(font
					(size 1.27 1.27)
				)
				(hide yes)
			)
		)
		(property "Author" "Antmicro"
			(at 199.39 82.55 0)
			(effects
				(font
					(size 1.27 1.27)
					(thickness 0.15)
				)
				(justify left bottom)
				(hide yes)
			)
		)
		(property "License" "Apache-2.0"
			(at 199.39 85.09 0)
			(effects
				(font
					(size 1.27 1.27)
					(thickness 0.15)
				)
				(justify left bottom)
				(hide yes)
			)
		)
		(pin "1"
		)
		(instances
			(project "com-express-7-baseboard"
				(path ""
					(reference "#PWR0165")
					(unit 1)
				)
			)
		)
	)
	(symbol
		(lib_id "antmicroCapacitors0603:C_22u_16V_0603")
		(at 247.65 91.44 90)
		(unit 1)
		(exclude_from_sim no)
		(in_bom yes)
		(on_board yes)
		(dnp no)
		(fields_autoplaced yes)
		(property "Reference" "C76"
			(at 250.19 87.6235 90)
			(effects
				(font
					(size 1.27 1.27)
					(thickness 0.15)
				)
				(justify right)
			)
		)
		(property "Value" "C_22u_16V_0603"
			(at 257.81 71.12 0)
			(effects
				(font
					(size 1.27 1.27)
					(thickness 0.15)
				)
				(justify left bottom)
				(hide yes)
			)
		)
		(property "Footprint" "antmicro-footprints:C_0603_1608Metric"
			(at 260.35 71.12 0)
			(effects
				(font
					(size 1.27 1.27)
					(thickness 0.15)
				)
				(justify left bottom)
				(hide yes)
			)
		)
		(property "Datasheet" "https://product.samsungsem.com/mlcc/CL10A226MO7JZN.do"
			(at 262.89 71.12 0)
			(effects
				(font
					(size 1.27 1.27)
					(thickness 0.15)
				)
				(justify left bottom)
				(hide yes)
			)
		)
		(property "Description" ""
			(at 247.65 91.44 0)
			(effects
				(font
					(size 1.27 1.27)
				)
				(hide yes)
			)
		)
		(property "MPN" "CL10A226MO7JZNC"
			(at 265.43 71.12 0)
			(effects
				(font
					(size 1.27 1.27)
					(thickness 0.15)
				)
				(justify left bottom)
				(hide yes)
			)
		)
		(property "Manufacturer" "Samsung Electro-Mechanics"
			(at 267.97 71.12 0)
			(effects
				(font
					(size 1.27 1.27)
					(thickness 0.15)
				)
				(justify left bottom)
				(hide yes)
			)
		)
		(property "License" "Apache-2.0"
			(at 270.51 71.12 0)
			(effects
				(font
					(size 1.27 1.27)
					(thickness 0.15)
				)
				(justify left bottom)
				(hide yes)
			)
		)
		(property "Author" "Antmicro"
			(at 273.05 71.12 0)
			(effects
				(font
					(size 1.27 1.27)
					(thickness 0.15)
				)
				(justify left bottom)
				(hide yes)
			)
		)
		(property "Val" "22u"
			(at 250.19 90.1635 90)
			(effects
				(font
					(size 1.27 1.27)
					(thickness 0.15)
				)
				(justify right)
			)
		)
		(property "Voltage" "16V"
			(at 275.59 71.12 0)
			(effects
				(font
					(size 1.27 1.27)
				)
				(justify left bottom)
				(hide yes)
			)
		)
		(property "Dielectric" ""
			(at 278.13 71.12 0)
			(effects
				(font
					(size 1.27 1.27)
				)
				(justify left bottom)
				(hide yes)
			)
		)
		(property "Public" "False"
			(at 280.67 71.12 0)
			(effects
				(font
					(size 1.27 1.27)
				)
				(justify left bottom)
				(hide yes)
			)
		)
		(pin "2"
		)
		(pin "1"
		)
		(instances
			(project "com-express-7-baseboard"
				(path ""
					(reference "C76")
					(unit 1)
				)
			)
		)
	)
	(symbol
		(lib_id "antmicroLEDIndicationDiscrete:LED_G_0603_LTST-C190GKT")
		(at 232.41 142.24 90)
		(unit 1)
		(exclude_from_sim no)
		(in_bom yes)
		(on_board yes)
		(dnp no)
		(property "Reference" "D14"
			(at 233.68 138.43 90)
			(effects
				(font
					(size 1.27 1.27)
				)
				(justify right)
			)
		)
		(property "Value" "LED_G_0603_LTST-C190GKT"
			(at 228.6 139.7 0)
			(effects
				(font
					(size 1.27 1.27)
					(thickness 0.15)
				)
				(justify left bottom)
				(hide yes)
			)
		)
		(property "Footprint" "antmicro-footprints:LED_0603_1608Metric_G"
			(at 242.57 119.38 0)
			(effects
				(font
					(size 1.27 1.27)
					(thickness 0.15)
				)
				(justify left bottom)
				(hide yes)
			)
		)
		(property "Datasheet" "https://media.digikey.com/pdf/Data%20Sheets/Lite-On%20PDFs/LTST-C190GKT.pdf"
			(at 245.11 119.38 0)
			(effects
				(font
					(size 1.27 1.27)
					(thickness 0.15)
				)
				(justify left bottom)
				(hide yes)
			)
		)
		(property "Description" ""
			(at 232.41 142.24 0)
			(effects
				(font
					(size 1.27 1.27)
				)
				(hide yes)
			)
		)
		(property "MPN" "LTST-C190GKT"
			(at 229.235 136.525 90)
			(effects
				(font
					(size 1.27 1.27)
					(thickness 0.15)
				)
				(justify left bottom)
				(hide yes)
			)
		)
		(property "Manufacturer" "Lite-On"
			(at 250.19 119.38 0)
			(effects
				(font
					(size 1.27 1.27)
					(thickness 0.15)
				)
				(justify left bottom)
				(hide yes)
			)
		)
		(property "Author" "Antmicro"
			(at 252.73 119.38 0)
			(effects
				(font
					(size 1.27 1.27)
					(thickness 0.15)
				)
				(justify left bottom)
				(hide yes)
			)
		)
		(property "License" "Apache-2.0"
			(at 255.27 119.38 0)
			(effects
				(font
					(size 1.27 1.27)
					(thickness 0.15)
				)
				(justify left bottom)
				(hide yes)
			)
		)
		(property "Public" "False"
			(at 250.19 121.92 0)
			(effects
				(font
					(size 1.27 1.27)
				)
				(justify left bottom)
				(hide yes)
			)
		)
		(property "Color" "Green"
			(at 233.68 140.97 90)
			(effects
				(font
					(size 1.27 1.27)
				)
				(justify right)
			)
		)
		(pin "1"
		)
		(pin "2"
		)
		(instances
			(project "com-express-7-baseboard"
				(path ""
					(reference "D14")
					(unit 1)
				)
			)
		)
	)
	(symbol
		(lib_id "antmicroCapacitors0603:C_22u_16V_0603")
		(at 237.49 91.44 90)
		(unit 1)
		(exclude_from_sim no)
		(in_bom yes)
		(on_board yes)
		(dnp no)
		(fields_autoplaced yes)
		(property "Reference" "C75"
			(at 240.03 87.6235 90)
			(effects
				(font
					(size 1.27 1.27)
					(thickness 0.15)
				)
				(justify right)
			)
		)
		(property "Value" "C_22u_16V_0603"
			(at 247.65 71.12 0)
			(effects
				(font
					(size 1.27 1.27)
					(thickness 0.15)
				)
				(justify left bottom)
				(hide yes)
			)
		)
		(property "Footprint" "antmicro-footprints:C_0603_1608Metric"
			(at 250.19 71.12 0)
			(effects
				(font
					(size 1.27 1.27)
					(thickness 0.15)
				)
				(justify left bottom)
				(hide yes)
			)
		)
		(property "Datasheet" "https://product.samsungsem.com/mlcc/CL10A226MO7JZN.do"
			(at 252.73 71.12 0)
			(effects
				(font
					(size 1.27 1.27)
					(thickness 0.15)
				)
				(justify left bottom)
				(hide yes)
			)
		)
		(property "Description" ""
			(at 237.49 91.44 0)
			(effects
				(font
					(size 1.27 1.27)
				)
				(hide yes)
			)
		)
		(property "MPN" "CL10A226MO7JZNC"
			(at 255.27 71.12 0)
			(effects
				(font
					(size 1.27 1.27)
					(thickness 0.15)
				)
				(justify left bottom)
				(hide yes)
			)
		)
		(property "Manufacturer" "Samsung Electro-Mechanics"
			(at 257.81 71.12 0)
			(effects
				(font
					(size 1.27 1.27)
					(thickness 0.15)
				)
				(justify left bottom)
				(hide yes)
			)
		)
		(property "License" "Apache-2.0"
			(at 260.35 71.12 0)
			(effects
				(font
					(size 1.27 1.27)
					(thickness 0.15)
				)
				(justify left bottom)
				(hide yes)
			)
		)
		(property "Author" "Antmicro"
			(at 262.89 71.12 0)
			(effects
				(font
					(size 1.27 1.27)
					(thickness 0.15)
				)
				(justify left bottom)
				(hide yes)
			)
		)
		(property "Val" "22u"
			(at 240.03 90.1635 90)
			(effects
				(font
					(size 1.27 1.27)
					(thickness 0.15)
				)
				(justify right)
			)
		)
		(property "Voltage" "16V"
			(at 265.43 71.12 0)
			(effects
				(font
					(size 1.27 1.27)
				)
				(justify left bottom)
				(hide yes)
			)
		)
		(property "Dielectric" ""
			(at 267.97 71.12 0)
			(effects
				(font
					(size 1.27 1.27)
				)
				(justify left bottom)
				(hide yes)
			)
		)
		(property "Public" "False"
			(at 270.51 71.12 0)
			(effects
				(font
					(size 1.27 1.27)
				)
				(justify left bottom)
				(hide yes)
			)
		)
		(pin "2"
		)
		(pin "1"
		)
		(instances
			(project "com-express-7-baseboard"
				(path ""
					(reference "C75")
					(unit 1)
				)
			)
		)
	)
	(symbol
		(lib_id "antmicropower:GND")
		(at 247.65 92.71 0)
		(unit 1)
		(exclude_from_sim no)
		(in_bom yes)
		(on_board yes)
		(dnp no)
		(property "Reference" "#PWR0170"
			(at 247.65 99.06 0)
			(effects
				(font
					(size 1.27 1.27)
				)
				(justify left bottom)
				(hide yes)
			)
		)
		(property "Value" "GND"
			(at 245.745 97.79 0)
			(effects
				(font
					(size 1.27 1.27)
				)
				(justify left bottom)
			)
		)
		(property "Footprint" ""
			(at 247.65 92.71 0)
			(effects
				(font
					(size 1.27 1.27)
				)
				(justify left bottom)
				(hide yes)
			)
		)
		(property "Datasheet" ""
			(at 247.65 92.71 0)
			(effects
				(font
					(size 1.27 1.27)
				)
				(justify left bottom)
				(hide yes)
			)
		)
		(property "Description" ""
			(at 247.65 92.71 0)
			(effects
				(font
					(size 1.27 1.27)
				)
				(hide yes)
			)
		)
		(property "Author" "Antmicro"
			(at 256.54 100.33 0)
			(effects
				(font
					(size 1.27 1.27)
					(thickness 0.15)
				)
				(justify left bottom)
				(hide yes)
			)
		)
		(property "License" "Apache-2.0"
			(at 256.54 102.87 0)
			(effects
				(font
					(size 1.27 1.27)
					(thickness 0.15)
				)
				(justify left bottom)
				(hide yes)
			)
		)
		(pin "1"
		)
		(instances
			(project "com-express-7-baseboard"
				(path ""
					(reference "#PWR0170")
					(unit 1)
				)
			)
		)
	)
	(symbol
		(lib_id "antmicropower:GND")
		(at 257.81 92.71 0)
		(unit 1)
		(exclude_from_sim no)
		(in_bom yes)
		(on_board yes)
		(dnp no)
		(property "Reference" "#PWR0171"
			(at 257.81 99.06 0)
			(effects
				(font
					(size 1.27 1.27)
				)
				(justify left bottom)
				(hide yes)
			)
		)
		(property "Value" "GND"
			(at 255.905 97.79 0)
			(effects
				(font
					(size 1.27 1.27)
				)
				(justify left bottom)
			)
		)
		(property "Footprint" ""
			(at 257.81 92.71 0)
			(effects
				(font
					(size 1.27 1.27)
				)
				(justify left bottom)
				(hide yes)
			)
		)
		(property "Datasheet" ""
			(at 257.81 92.71 0)
			(effects
				(font
					(size 1.27 1.27)
				)
				(justify left bottom)
				(hide yes)
			)
		)
		(property "Description" ""
			(at 257.81 92.71 0)
			(effects
				(font
					(size 1.27 1.27)
				)
				(hide yes)
			)
		)
		(property "Author" "Antmicro"
			(at 266.7 100.33 0)
			(effects
				(font
					(size 1.27 1.27)
					(thickness 0.15)
				)
				(justify left bottom)
				(hide yes)
			)
		)
		(property "License" "Apache-2.0"
			(at 266.7 102.87 0)
			(effects
				(font
					(size 1.27 1.27)
					(thickness 0.15)
				)
				(justify left bottom)
				(hide yes)
			)
		)
		(pin "1"
		)
		(instances
			(project "com-express-7-baseboard"
				(path ""
					(reference "#PWR0171")
					(unit 1)
				)
			)
		)
	)
	(symbol
		(lib_id "antmicroResistors0603:R_0R_22.4A_0603")
		(at 267.97 81.28 90)
		(unit 1)
		(exclude_from_sim no)
		(in_bom yes)
		(on_board yes)
		(dnp no)
		(fields_autoplaced yes)
		(property "Reference" "R131"
			(at 270.51 76.2 90)
			(effects
				(font
					(size 1.27 1.27)
				)
				(justify right)
			)
		)
		(property "Value" "R_0R_22.4A_0603"
			(at 270.51 77.47 90)
			(effects
				(font
					(size 1.27 1.27)
					(thickness 0.15)
				)
				(justify right)
				(hide yes)
			)
		)
		(property "Footprint" "antmicro-footprints:R_0603_1608Metric"
			(at 280.67 58.42 0)
			(effects
				(font
					(size 1.27 1.27)
					(thickness 0.15)
				)
				(justify left bottom)
				(hide yes)
			)
		)
		(property "Datasheet" "https://fscdn.rohm.com/en/products/databook/datasheet/passive/resistor/chip_resistor/pmr-jpw-e.pdf"
			(at 283.21 58.42 0)
			(effects
				(font
					(size 1.27 1.27)
					(thickness 0.15)
				)
				(justify left bottom)
				(hide yes)
			)
		)
		(property "Description" ""
			(at 267.97 81.28 0)
			(effects
				(font
					(size 1.27 1.27)
				)
				(hide yes)
			)
		)
		(property "Manufacturer" "ROHM Semiconductor"
			(at 285.75 58.42 0)
			(effects
				(font
					(size 1.27 1.27)
					(thickness 0.15)
				)
				(justify left bottom)
				(hide yes)
			)
		)
		(property "MPN" "PMR03EZPJ000"
			(at 288.29 58.42 0)
			(effects
				(font
					(size 1.27 1.27)
					(thickness 0.15)
				)
				(justify left bottom)
				(hide yes)
			)
		)
		(property "Val" "0R"
			(at 270.51 78.74 90)
			(effects
				(font
					(size 1.27 1.27)
					(thickness 0.15)
				)
				(justify right)
			)
		)
		(property "Author" "Antmicro"
			(at 290.83 58.42 0)
			(effects
				(font
					(size 1.27 1.27)
					(thickness 0.15)
				)
				(justify left bottom)
				(hide yes)
			)
		)
		(property "License" "Apache-2.0"
			(at 293.37 58.42 0)
			(effects
				(font
					(size 1.27 1.27)
					(thickness 0.15)
				)
				(justify left bottom)
				(hide yes)
			)
		)
		(property "Max. Curr." "22.4A"
			(at 270.51 81.28 90)
			(effects
				(font
					(size 1.27 1.27)
					(thickness 0.15)
				)
				(justify right)
			)
		)
		(property "Tolerance" "template_tolerance"
			(at 278.13 60.96 0)
			(effects
				(font
					(size 1.27 1.27)
				)
				(justify left bottom)
				(hide yes)
			)
		)
		(property "Public" "False"
			(at 298.45 60.96 0)
			(effects
				(font
					(size 1.27 1.27)
				)
				(justify left bottom)
				(hide yes)
			)
		)
		(pin "1"
		)
		(pin "2"
		)
		(instances
			(project "com-express-7-baseboard"
				(path ""
					(reference "R131")
					(unit 1)
				)
			)
		)
	)
	(symbol
		(lib_id "antmicroPciConnectors:Bus_M.2_1-2199230-6")
		(at 200.66 88.9 0)
		(unit 1)
		(exclude_from_sim no)
		(in_bom yes)
		(on_board yes)
		(dnp no)
		(fields_autoplaced yes)
		(property "Reference" "J8"
			(at 215.9 81.28 0)
			(effects
				(font
					(size 1.27 1.27)
					(thickness 0.15)
				)
			)
		)
		(property "Value" "Bus_M.2_1-2199230-6"
			(at 246.38 96.52 0)
			(effects
				(font
					(size 1.27 1.27)
					(thickness 0.15)
				)
				(justify left bottom)
				(hide yes)
			)
		)
		(property "Footprint" "antmicro-footprints:Bus_M.2_Socket_Key_M_TE_1-2199230-6"
			(at 246.38 99.06 0)
			(effects
				(font
					(size 1.27 1.27)
					(thickness 0.15)
				)
				(justify left bottom)
				(hide yes)
			)
		)
		(property "Datasheet" "https://www.te.com/commerce/DocumentDelivery/DDEController?Action=srchrtrv&DocNm=2199230&DocType=Customer+Drawing&DocLang=English"
			(at 246.38 101.6 0)
			(effects
				(font
					(size 1.27 1.27)
					(thickness 0.15)
				)
				(justify left bottom)
				(hide yes)
			)
		)
		(property "Description" ""
			(at 200.66 88.9 0)
			(effects
				(font
					(size 1.27 1.27)
				)
				(hide yes)
			)
		)
		(property "Manufacturer" "TE Connectivity"
			(at 246.38 104.14 0)
			(effects
				(font
					(size 1.27 1.27)
					(thickness 0.15)
				)
				(justify left bottom)
				(hide yes)
			)
		)
		(property "MPN" "1-2199230-6"
			(at 215.9 83.82 0)
			(effects
				(font
					(size 1.27 1.27)
					(thickness 0.15)
				)
			)
		)
		(property "Author" "Antmicro"
			(at 246.38 106.68 0)
			(effects
				(font
					(size 1.27 1.27)
					(thickness 0.15)
				)
				(justify left bottom)
				(hide yes)
			)
		)
		(property "License" "Apache-2.0"
			(at 246.38 109.22 0)
			(effects
				(font
					(size 1.27 1.27)
					(thickness 0.15)
				)
				(justify left bottom)
				(hide yes)
			)
		)
		(pin "1"
		)
		(pin "10"
		)
		(pin "11"
		)
		(pin "12"
		)
		(pin "13"
		)
		(pin "14"
		)
		(pin "15"
		)
		(pin "16"
		)
		(pin "17"
		)
		(pin "18"
		)
		(pin "19"
		)
		(pin "2"
		)
		(pin "20"
		)
		(pin "21"
		)
		(pin "22"
		)
		(pin "23"
		)
		(pin "24"
		)
		(pin "25"
		)
		(pin "26"
		)
		(pin "27"
		)
		(pin "28"
		)
		(pin "29"
		)
		(pin "3"
		)
		(pin "30"
		)
		(pin "31"
		)
		(pin "32"
		)
		(pin "33"
		)
		(pin "34"
		)
		(pin "35"
		)
		(pin "36"
		)
		(pin "37"
		)
		(pin "38"
		)
		(pin "39"
		)
		(pin "4"
		)
		(pin "40"
		)
		(pin "41"
		)
		(pin "42"
		)
		(pin "43"
		)
		(pin "44"
		)
		(pin "45"
		)
		(pin "46"
		)
		(pin "47"
		)
		(pin "48"
		)
		(pin "49"
		)
		(pin "5"
		)
		(pin "50"
		)
		(pin "51"
		)
		(pin "52"
		)
		(pin "53"
		)
		(pin "54"
		)
		(pin "55"
		)
		(pin "56"
		)
		(pin "57"
		)
		(pin "58"
		)
		(pin "6"
		)
		(pin "67"
		)
		(pin "68"
		)
		(pin "69"
		)
		(pin "7"
		)
		(pin "70"
		)
		(pin "71"
		)
		(pin "72"
		)
		(pin "73"
		)
		(pin "74"
		)
		(pin "75"
		)
		(pin "8"
		)
		(pin "9"
		)
		(pin "MP1"
		)
		(pin "MP2"
		)
		(instances
			(project "com-express-7-baseboard"
				(path ""
					(reference "J8")
					(unit 1)
				)
			)
		)
	)
	(symbol
		(lib_id "antmicroModules:Mech_M2_2280_H2.5mm")
		(at 210.82 182.88 0)
		(unit 1)
		(exclude_from_sim no)
		(in_bom no)
		(on_board yes)
		(dnp no)
		(fields_autoplaced yes)
		(property "Reference" "A1"
			(at 222.25 184.7849 0)
			(effects
				(font
					(size 1.27 1.27)
					(thickness 0.15)
				)
				(justify left)
			)
		)
		(property "Value" "Mech_M2_2280_H2.5mm"
			(at 222.25 187.3249 0)
			(effects
				(font
					(size 1.27 1.27)
					(thickness 0.15)
				)
				(justify left)
			)
		)
		(property "Footprint" "antmicro-footprints:Mech_M2_2280_H2.5mm"
			(at 236.22 187.96 0)
			(effects
				(font
					(size 1.27 1.27)
					(thickness 0.15)
				)
				(justify left bottom)
				(hide yes)
			)
		)
		(property "Datasheet" ""
			(at 236.22 190.5 0)
			(effects
				(font
					(size 1.27 1.27)
					(thickness 0.15)
				)
				(justify left bottom)
				(hide yes)
			)
		)
		(property "Description" ""
			(at 210.82 182.88 0)
			(effects
				(font
					(size 1.27 1.27)
				)
				(hide yes)
			)
		)
		(property "Manufacturer" ""
			(at 210.82 182.88 0)
			(effects
				(font
					(size 1.27 1.27)
				)
				(hide yes)
			)
		)
		(property "MPN" ""
			(at 210.82 182.88 0)
			(effects
				(font
					(size 1.27 1.27)
				)
			)
		)
		(property "Author" "Antmicro"
			(at 236.22 193.04 0)
			(effects
				(font
					(size 1.27 1.27)
					(thickness 0.15)
				)
				(justify left bottom)
				(hide yes)
			)
		)
		(property "License" "Apache-2.0"
			(at 236.22 195.58 0)
			(effects
				(font
					(size 1.27 1.27)
					(thickness 0.15)
				)
				(justify left bottom)
				(hide yes)
			)
		)
		(property "Public" "False"
			(at 236.22 198.12 0)
			(effects
				(font
					(size 1.27 1.27)
				)
				(justify left bottom)
				(hide yes)
			)
		)
		(instances
			(project "com-express-7-baseboard"
				(path ""
					(reference "A1")
					(unit 1)
				)
			)
		)
	)
	(symbol
		(lib_id "antmicropower:GND")
		(at 232.41 167.64 0)
		(unit 1)
		(exclude_from_sim no)
		(in_bom yes)
		(on_board yes)
		(dnp no)
		(property "Reference" "#PWR0168"
			(at 232.41 173.99 0)
			(effects
				(font
					(size 1.27 1.27)
				)
				(justify left bottom)
				(hide yes)
			)
		)
		(property "Value" "GND"
			(at 230.505 172.72 0)
			(effects
				(font
					(size 1.27 1.27)
				)
				(justify left bottom)
			)
		)
		(property "Footprint" ""
			(at 232.41 167.64 0)
			(effects
				(font
					(size 1.27 1.27)
				)
				(justify left bottom)
				(hide yes)
			)
		)
		(property "Datasheet" ""
			(at 232.41 167.64 0)
			(effects
				(font
					(size 1.27 1.27)
				)
				(justify left bottom)
				(hide yes)
			)
		)
		(property "Description" ""
			(at 232.41 167.64 0)
			(effects
				(font
					(size 1.27 1.27)
				)
				(hide yes)
			)
		)
		(property "Author" "Antmicro"
			(at 241.3 175.26 0)
			(effects
				(font
					(size 1.27 1.27)
					(thickness 0.15)
				)
				(justify left bottom)
				(hide yes)
			)
		)
		(property "License" "Apache-2.0"
			(at 241.3 177.8 0)
			(effects
				(font
					(size 1.27 1.27)
					(thickness 0.15)
				)
				(justify left bottom)
				(hide yes)
			)
		)
		(pin "1"
		)
		(instances
			(project "com-express-7-baseboard"
				(path ""
					(reference "#PWR0168")
					(unit 1)
				)
			)
		)
	)
)
